(kicad_sch (version 20230121) (generator eeschema)

  (paper "A3")

  (title_block
    (title "Scalenode CM4 Baseboard")
    (date "2024-03-26")
    (rev "1.1.3")
    (company "Antmicro")
    (comment 1 "www.antmicro.com")
  )

  (symbol (lib_id "scalenode-cm4-baseboard:antmicro_logo") (at 101.6 266.7 0) (unit 1)
    (in_bom yes) (on_board yes) (dnp no) (fields_autoplaced)
    (property "Reference" "N1" (at 107.95 264.4075 0)
      (effects (font (size 1.27 1.27) (thickness 0.15)) (justify left bottom))
    )
    (property "Value" "antmicro_logo" (at 107.95 266.9475 0)
      (effects (font (size 1.27 1.27) (thickness 0.15)) (justify left bottom))
    )
    (property "Footprint" "scalenode-cm4-baseboard-footprints:antmicro-logo" (at 116.84 276.86 0)
      (effects (font (size 1.27 1.27) (thickness 0.15)) (justify left bottom) hide)
    )
    (property "Datasheet" "" (at 116.84 279.4 0)
      (effects (font (size 1.27 1.27) (thickness 0.15)) (justify left bottom) hide)
    )
    (property "Author" "Antmicro" (at 116.84 281.94 0)
      (effects (font (size 1.27 1.27) (thickness 0.15)) (justify left bottom) hide)
    )
    (property "License" "Apache-2.0" (at 116.84 284.48 0)
      (effects (font (size 1.27 1.27) (thickness 0.15)) (justify left bottom) hide)
    )
    (property "Manufacturer" "" (at 116.84 287.02 0)
      (effects (font (size 1.27 1.27) (thickness 0.15)) (justify left bottom) hide)
    )
    (property "MPN" "" (at 101.6 266.7 0)
      (effects (font (size 1.27 1.27)) hide)
    )
    (instances
      (project "scalenode-cm4-baseboard"
        (path ""
          (reference "N1") (unit 1)
        )
      )
    )
  )

  (symbol (lib_id "scalenode-cm4-baseboard:oshw_logo") (at 139.7 266.7 0) (unit 1)
    (in_bom yes) (on_board yes) (dnp no) (fields_autoplaced)
    (property "Reference" "N3" (at 146.05 264.4075 0)
      (effects (font (size 1.27 1.27) (thickness 0.15)) (justify left bottom))
    )
    (property "Value" "oshw_logo" (at 146.05 266.9475 0)
      (effects (font (size 1.27 1.27) (thickness 0.15)) (justify left bottom))
    )
    (property "Footprint" "scalenode-cm4-baseboard-footprints:oshw-logo" (at 154.94 276.86 0)
      (effects (font (size 1.27 1.27) (thickness 0.15)) (justify left bottom) hide)
    )
    (property "Datasheet" "" (at 154.94 279.4 0)
      (effects (font (size 1.27 1.27) (thickness 0.15)) (justify left bottom) hide)
    )
    (property "Author" "Antmicro" (at 154.94 281.94 0)
      (effects (font (size 1.27 1.27) (thickness 0.15)) (justify left bottom) hide)
    )
    (property "License" "Apache-2.0" (at 154.94 284.48 0)
      (effects (font (size 1.27 1.27) (thickness 0.15)) (justify left bottom) hide)
    )
    (property "Manufacturer" "" (at 154.94 287.02 0)
      (effects (font (size 1.27 1.27) (thickness 0.15)) (justify left bottom) hide)
    )
    (property "MPN" "" (at 139.7 266.7 0)
      (effects (font (size 1.27 1.27)) hide)
    )
    (instances
      (project "scalenode-cm4-baseboard"
        (path ""
          (reference "N3") (unit 1)
        )
      )
    )
  )

  (sheet (at 50.8 189.23) (size 38.1 25.4) (fields_autoplaced)
    (stroke (width 0) (type solid))
    (fill (color 0 0 0 0.0000))
    (property "Sheetname" "Compute module" (at 50.8 188.5184 0)
      (effects (font (size 1.27 1.27)) (justify left bottom))
    )
    (property "Sheetfile" "compute-module.kicad_sch" (at 50.8 215.2146 0)
      (effects (font (size 1.27 1.27)) (justify left top))
    )
    (instances
      (project "scalenode-cm4-baseboard"
        (path "" (page "2"))
      )
    )
  )

  (sheet (at 241.3 190.5) (size 38.1 25.4) (fields_autoplaced)
    (stroke (width 0) (type solid))
    (fill (color 0 0 0 0.0000))
    (property "Sheetname" "PoE" (at 241.3 189.7884 0)
      (effects (font (size 1.27 1.27)) (justify left bottom))
    )
    (property "Sheetfile" "poe.kicad_sch" (at 241.3 216.4846 0)
      (effects (font (size 1.27 1.27)) (justify left top))
    )
    (instances
      (project "scalenode-cm4-baseboard"
        (path "" (page "5"))
      )
    )
  )

  (sheet (at 114.3 190.5) (size 38.1 25.4) (fields_autoplaced)
    (stroke (width 0) (type solid))
    (fill (color 0 0 0 0.0000))
    (property "Sheetname" "Supply" (at 114.3 189.7884 0)
      (effects (font (size 1.27 1.27)) (justify left bottom))
    )
    (property "Sheetfile" "supply.kicad_sch" (at 114.3 216.4846 0)
      (effects (font (size 1.27 1.27)) (justify left top))
    )
    (instances
      (project "scalenode-cm4-baseboard"
        (path "" (page "3"))
      )
    )
  )

  (sheet (at 177.8 190.5) (size 38.1 25.4) (fields_autoplaced)
    (stroke (width 0) (type solid))
    (fill (color 0 0 0 0.0000))
    (property "Sheetname" "Interfaces" (at 177.8 189.7884 0)
      (effects (font (size 1.27 1.27)) (justify left bottom))
    )
    (property "Sheetfile" "interfaces.kicad_sch" (at 177.8 216.4846 0)
      (effects (font (size 1.27 1.27)) (justify left top))
    )
    (instances
      (project "scalenode-cm4-baseboard"
        (path "" (page "4"))
      )
    )
  )

  (sheet (at 304.8 190.5) (size 38.1 25.4) (fields_autoplaced)
    (stroke (width 0) (type solid))
    (fill (color 0 0 0 0.0000))
    (property "Sheetname" "NVMe SSD" (at 304.8 189.7884 0)
      (effects (font (size 1.27 1.27)) (justify left bottom))
    )
    (property "Sheetfile" "nvme-ssd.kicad_sch" (at 304.8 216.4846 0)
      (effects (font (size 1.27 1.27)) (justify left top))
    )
    (instances
      (project "scalenode-cm4-baseboard"
        (path "" (page "6"))
      )
    )
  )

  (sheet (at 354.965 190.5) (size 38.1 25.4) (fields_autoplaced)
    (stroke (width 0) (type solid))
    (fill (color 0 0 0 0.0000))
    (property "Sheetname" "Expansion connectors" (at 354.965 189.7884 0)
      (effects (font (size 1.27 1.27)) (justify left bottom))
    )
    (property "Sheetfile" "expansion-connectors.kicad_sch" (at 354.965 216.4846 0)
      (effects (font (size 1.27 1.27)) (justify left top))
    )
    (instances
      (project "scalenode-cm4-baseboard"
        (path "" (page "7"))
      )
    )
  )

  (sheet_instances
    (path "/" (page "1"))
  )
)
